# S9S_MB_2U (Grand Teton) — schematic netlist excerpt (pin names and nets, part order shuffled) for the footprints in the layout excerpt that follows; sources: Cadence DE-HDL packaged netlist, KiCad conversion of 03242023_DA0F0TMBIJ0_F0T_Motherboard_J_brd_V01_OCP.brd

PC334  Q_CAP  0.1UF 25V 10% EMPTY  pkg 0402  page 266 : A = PVCCIN_CPU0_VCC ; B = GND
PC395  Q_CAP  2.2UF 10V 10% X6S  pkg C0402  page 289 : A = PVCCFA_EHV_FIVRA_CPU1_VDD1 ; B = GND

(kicad_pcb
	(version 20260206)
	(generator "pcbnew")
	(generator_version "10.0")
	(general
		(thickness 1.6)
		(legacy_teardrops no)
	)
	(paper "A4")
	(title_block
		(title "03242023_DA0F0TMBIJ0_F0T_Motherboard_J_brd_V01_OCP.brd")
		(comment 1 "Grand Teton / footprints 3183-3184 of 6105")
	)
	(layers
		(0 "F.Cu" signal "TOP")
		(4 "In1.Cu" signal "GND")
		(6 "In2.Cu" signal "IN1")
		(8 "In3.Cu" signal "GND1")
		(10 "In4.Cu" signal "IN2")
		(12 "In5.Cu" signal "GND2")
		(14 "In6.Cu" signal "IN3")
		(16 "In7.Cu" signal "GND3")
		(18 "In8.Cu" signal "VCC")
		(20 "In9.Cu" signal "VCC1")
		(22 "In10.Cu" signal "GND4")
		(24 "In11.Cu" signal "IN4")
		(26 "In12.Cu" signal "GND5")
		(28 "In13.Cu" signal "IN5")
		(30 "In14.Cu" signal "GND6")
		(32 "In15.Cu" signal "IN6")
		(34 "In16.Cu" signal "GND7")
		(2 "B.Cu" signal "BOTTOM")
		(9 "F.Adhes" user "F.Adhesive")
		(11 "B.Adhes" user "B.Adhesive")
		(13 "F.Paste" user "Package Geometry/Pastemask Top")
		(15 "B.Paste" user "Package Geometry/Pastemask Bottom")
		(5 "F.SilkS" user "Ref Des/Silkscreen Top")
		(7 "B.SilkS" user "Ref Des/Silkscreen Bottom")
		(1 "F.Mask" user "Board Geometry/Soldermask Top")
		(3 "B.Mask" user "Board Geometry/Soldermask Bottom")
		(17 "Dwgs.User" user "User.Drawings")
		(19 "Cmts.User" user "User.Comments")
		(21 "Eco1.User" user "User.Eco1")
		(23 "Eco2.User" user "User.Eco2")
		(25 "Edge.Cuts" user "Board Geometry/Outline")
		(27 "Margin" user)
		(31 "F.CrtYd" user "Package Geometry/Place Bound Top")
		(29 "B.CrtYd" user "Package Geometry/Place Bound Bottom")
		(35 "F.Fab" user "Ref Des/Assembly Top")
		(33 "B.Fab" user "Ref Des/Assembly Bottom")
	)
	(footprint ""
		(layer "F.Cu")
		(at 168.449498 -356.03053 90)
		(property "Reference" "PC395"
			(at 0 0 90)
			(layer "F.SilkS")
			(hide yes)
			(effects
				(font
					(size 1.27 1.27)
				)
			)
		)
		(property "Value" ""
			(at 0 0 90)
			(layer "F.Fab")
			(effects
				(font
					(size 1.27 1.27)
				)
			)
		)
		(duplicate_pad_numbers_are_jumpers no)
		(fp_line
			(start 0.7874 -0.4064)
			(end 0.7874 0.4064)
			(stroke
				(width 0.1524)
				(type default)
			)
			(layer "F.SilkS")
		)
		(fp_line
			(start -0.7874 -0.4064)
			(end 0.7874 -0.4064)
			(stroke
				(width 0.1524)
				(type default)
			)
			(layer "F.SilkS")
		)
		(fp_line
			(start 0.7874 0.4064)
			(end -0.7874 0.4064)
			(stroke
				(width 0.1524)
				(type default)
			)
			(layer "F.SilkS")
		)
		(fp_line
			(start -0.7874 0.4064)
			(end -0.7874 -0.4064)
			(stroke
				(width 0.1524)
				(type default)
			)
			(layer "F.SilkS")
		)
		(fp_line
			(start -0.12065 -0.305054)
			(end -0.12065 -0.2794)
			(stroke
				(width 0.1)
				(type default)
			)
			(layer "F.Fab")
		)
		(fp_line
			(start -0.67945 -0.305054)
			(end -0.12065 -0.305054)
			(stroke
				(width 0.1)
				(type default)
			)
			(layer "F.Fab")
		)
		(fp_line
			(start 0.67945 -0.3048)
			(end 0.67945 0.3048)
			(stroke
				(width 0.1)
				(type default)
			)
			(layer "F.Fab")
		)
		(fp_line
			(start 0.12065 -0.3048)
			(end 0.67945 -0.3048)
			(stroke
				(width 0.1)
				(type default)
			)
			(layer "F.Fab")
		)
		(fp_line
			(start 0.12065 -0.2794)
			(end 0.12065 -0.3048)
			(stroke
				(width 0.1)
				(type default)
			)
			(layer "F.Fab")
		)
		(fp_line
			(start -0.12065 -0.2794)
			(end 0.12065 -0.2794)
			(stroke
				(width 0.1)
				(type default)
			)
			(layer "F.Fab")
		)
		(fp_line
			(start 0.120396 0.2794)
			(end -0.12065 0.2794)
			(stroke
				(width 0.1)
				(type default)
			)
			(layer "F.Fab")
		)
		(fp_line
			(start -0.12065 0.2794)
			(end -0.12065 0.3048)
			(stroke
				(width 0.1)
				(type default)
			)
			(layer "F.Fab")
		)
		(fp_line
			(start 0.67945 0.3048)
			(end 0.120396 0.3048)
			(stroke
				(width 0.1)
				(type default)
			)
			(layer "F.Fab")
		)
		(fp_line
			(start 0.120396 0.3048)
			(end 0.120396 0.2794)
			(stroke
				(width 0.1)
				(type default)
			)
			(layer "F.Fab")
		)
		(fp_line
			(start -0.12065 0.3048)
			(end -0.67945 0.3048)
			(stroke
				(width 0.1)
				(type default)
			)
			(layer "F.Fab")
		)
		(fp_line
			(start -0.67945 0.3048)
			(end -0.67945 -0.305054)
			(stroke
				(width 0.1)
				(type default)
			)
			(layer "F.Fab")
		)
		(pad "1" smd circle
			(at -0.40005 0 90)
			(size 0 0)
			(layers "F.Cu" "F.Mask" "F.Paste")
			(net "PVCCFA_EHV_FIVRA_CPU1_VDD1")
		)
		(pad "2" smd circle
			(at 0.40005 0 90)
			(size 0 0)
			(layers "F.Cu" "F.Mask" "F.Paste")
			(net "GND")
		)
	)
	(footprint ""
		(layer "F.Cu")
		(at 362.646468 -362.618528)
		(property "Reference" "PC334"
			(at 0 0 0)
			(layer "F.SilkS")
			(hide yes)
			(effects
				(font
					(size 1.27 1.27)
				)
			)
		)
		(property "Value" ""
			(at 0 0 0)
			(layer "F.Fab")
			(effects
				(font
					(size 1.27 1.27)
				)
			)
		)
		(duplicate_pad_numbers_are_jumpers no)
		(fp_line
			(start -0.7874 -0.4064)
			(end 0.7874 -0.4064)
			(stroke
				(width 0.1524)
				(type default)
			)
			(layer "F.SilkS")
		)
		(fp_line
			(start -0.7874 0.4064)
			(end -0.7874 -0.4064)
			(stroke
				(width 0.1524)
				(type default)
			)
			(layer "F.SilkS")
		)
		(fp_line
			(start 0.7874 -0.4064)
			(end 0.7874 0.4064)
			(stroke
				(width 0.1524)
				(type default)
			)
			(layer "F.SilkS")
		)
		(fp_line
			(start 0.7874 0.4064)
			(end -0.7874 0.4064)
			(stroke
				(width 0.1524)
				(type default)
			)
			(layer "F.SilkS")
		)
		(fp_line
			(start -0.67945 -0.305054)
			(end -0.12065 -0.305054)
			(stroke
				(width 0.1)
				(type default)
			)
			(layer "F.Fab")
		)
		(fp_line
			(start -0.67945 0.3048)
			(end -0.67945 -0.305054)
			(stroke
				(width 0.1)
				(type default)
			)
			(layer "F.Fab")
		)
		(fp_line
			(start -0.12065 -0.305054)
			(end -0.12065 -0.2794)
			(stroke
				(width 0.1)
				(type default)
			)
			(layer "F.Fab")
		)
		(fp_line
			(start -0.12065 -0.2794)
			(end 0.12065 -0.2794)
			(stroke
				(width 0.1)
				(type default)
			)
			(layer "F.Fab")
		)
		(fp_line
			(start -0.12065 0.2794)
			(end -0.12065 0.3048)
			(stroke
				(width 0.1)
				(type default)
			)
			(layer "F.Fab")
		)
		(fp_line
			(start -0.12065 0.3048)
			(end -0.67945 0.3048)
			(stroke
				(width 0.1)
				(type default)
			)
			(layer "F.Fab")
		)
		(fp_line
			(start 0.120396 0.2794)
			(end -0.12065 0.2794)
			(stroke
				(width 0.1)
				(type default)
			)
			(layer "F.Fab")
		)
		(fp_line
			(start 0.120396 0.3048)
			(end 0.120396 0.2794)
			(stroke
				(width 0.1)
				(type default)
			)
			(layer "F.Fab")
		)
		(fp_line
			(start 0.12065 -0.3048)
			(end 0.67945 -0.3048)
			(stroke
				(width 0.1)
				(type default)
			)
			(layer "F.Fab")
		)
		(fp_line
			(start 0.12065 -0.2794)
			(end 0.12065 -0.3048)
			(stroke
				(width 0.1)
				(type default)
			)
			(layer "F.Fab")
		)
		(fp_line
			(start 0.67945 -0.3048)
			(end 0.67945 0.3048)
			(stroke
				(width 0.1)
				(type default)
			)
			(layer "F.Fab")
		)
		(fp_line
			(start 0.67945 0.3048)
			(end 0.120396 0.3048)
			(stroke
				(width 0.1)
				(type default)
			)
			(layer "F.Fab")
		)
		(pad "1" smd circle
			(at -0.40005 0)
			(size 0 0)
			(layers "F.Cu" "F.Mask" "F.Paste")
			(net "PVCCIN_CPU0_VCC")
		)
		(pad "2" smd circle
			(at 0.40005 0)
			(size 0 0)
			(layers "F.Cu" "F.Mask" "F.Paste")
			(net "GND")
		)
	)
)
